(kicad_pcb
	(version 20260206)
	(generator "pcbnew")
	(generator_version "10.0")
	(general
		(thickness 1.6)
		(legacy_teardrops no)
	)
	(paper "A4")
	(title_block
		(title "Bryce Canyon_IOM_M2_16342-2_OCP.brd")
		(comment 1 "Bryce Canyon / footprints 8-15 of 1146")
	)
	(layers
		(0 "F.Cu" signal "TOP")
		(4 "In1.Cu" signal "L2GND")
		(6 "In2.Cu" signal "L3")
		(8 "In3.Cu" signal "L4VCC")
		(10 "In4.Cu" signal "L5VCC")
		(12 "In5.Cu" signal "L6")
		(14 "In6.Cu" signal "L7GND")
		(2 "B.Cu" signal "BOTTOM")
		(9 "F.Adhes" user "F.Adhesive")
		(11 "B.Adhes" user "B.Adhesive")
		(13 "F.Paste" user "Package Geometry/Pastemask Top")
		(15 "B.Paste" user "Package Geometry/Pastemask Bottom")
		(5 "F.SilkS" user "Ref Des/Silkscreen Top")
		(7 "B.SilkS" user "Ref Des/Silkscreen Bottom")
		(1 "F.Mask" user "Board Geometry/Soldermask Top")
		(3 "B.Mask" user "Board Geometry/Soldermask Bottom")
		(17 "Dwgs.User" user "User.Drawings")
		(19 "Cmts.User" user "User.Comments")
		(21 "Eco1.User" user "User.Eco1")
		(23 "Eco2.User" user "User.Eco2")
		(25 "Edge.Cuts" user "Board Geometry/Outline")
		(27 "Margin" user)
		(31 "F.CrtYd" user "Package Geometry/Place Bound Top")
		(29 "B.CrtYd" user "Package Geometry/Place Bound Bottom")
		(35 "F.Fab" user "Ref Des/Assembly Top")
		(33 "B.Fab" user "Ref Des/Assembly Bottom")
	)
	(footprint ""
		(layer "F.Cu")
		(at 18.650458 -175.96739 180)
		(property "Reference" "C229"
			(at 0 0 180)
			(layer "F.SilkS")
			(hide yes)
			(effects
				(font
					(size 1.27 1.27)
				)
			)
		)
		(property "Value" "SC1U16V3KX-5GP"
			(at 0 -2.8194 180)
			(unlocked yes)
			(layer "F.Fab")
			(hide yes)
			(effects
				(font
					(size 1.016 1.016)
					(thickness 0.1524)
				)
			)
		)
		(property "Device Type" "C603H36"
			(at 0 -4.3434 180)
			(unlocked yes)
			(layer "F.Fab")
			(hide yes)
			(effects
				(font
					(size 1.016 1.016)
					(thickness 0.1524)
				)
			)
		)
		(duplicate_pad_numbers_are_jumpers no)
		(fp_line
			(start 0.508 0)
			(end -0.508 0)
			(stroke
				(width 0.2032)
				(type default)
			)
			(layer "F.SilkS")
		)
		(fp_rect
			(start -0.5842 1.3335)
			(end 0.5842 -1.3335)
			(stroke
				(width 0)
				(type default)
			)
			(fill no)
			(layer "F.CrtYd")
		)
		(fp_rect
			(start -0.5842 1.3335)
			(end 0.5842 -1.3335)
			(stroke
				(width 0)
				(type default)
			)
			(fill no)
			(layer "F.Fab")
		)
		(pad "1" smd custom
			(at 0 -0.762 180)
			(size 0.2159 0.2159)
			(layers "F.Cu" "F.Mask" "F.Paste")
			(net "TPS74801_P1V2_STBY_BIAS")
			(options
				(clearance outline)
				(anchor circle)
			)
			(primitives
				(gr_poly
					(pts
						(arc
							(start -0.3302 -0.4318)
							(mid -0.402042 -0.402042)
							(end -0.4318 -0.3302)
						)
						(arc
							(start -0.4318 0.3302)
							(mid -0.402042 0.402042)
							(end -0.3302 0.4318)
						)
						(arc
							(start 0.3302 0.4318)
							(mid 0.402042 0.402042)
							(end 0.4318 0.3302)
						)
						(arc
							(start 0.4318 -0.3302)
							(mid 0.402042 -0.402042)
							(end 0.3302 -0.4318)
						)
					)
					(width 0)
					(fill yes)
				)
			)
		)
		(pad "2" smd custom
			(at 0 0.762 180)
			(size 0.2159 0.2159)
			(layers "F.Cu" "F.Mask" "F.Paste")
			(net "GND")
			(options
				(clearance outline)
				(anchor circle)
			)
			(primitives
				(gr_poly
					(pts
						(arc
							(start -0.3302 -0.4318)
							(mid -0.402042 -0.402042)
							(end -0.4318 -0.3302)
						)
						(arc
							(start -0.4318 0.3302)
							(mid -0.402042 0.402042)
							(end -0.3302 0.4318)
						)
						(arc
							(start 0.3302 0.4318)
							(mid 0.402042 0.402042)
							(end 0.4318 0.3302)
						)
						(arc
							(start 0.4318 -0.3302)
							(mid 0.402042 -0.402042)
							(end 0.3302 -0.4318)
						)
					)
					(width 0)
					(fill yes)
				)
			)
		)
	)
	(footprint ""
		(layer "F.Cu")
		(at 98.859594 -146.565874 90)
		(property "Reference" "C127"
			(at 0 0 90)
			(layer "F.SilkS")
			(hide yes)
			(effects
				(font
					(size 1.27 1.27)
				)
			)
		)
		(property "Value" "SCD1U16V2KX-3GP"
			(at 1.1811 -2.7051 90)
			(unlocked yes)
			(layer "F.Fab")
			(hide yes)
			(effects
				(font
					(size 1.016 1.016)
					(thickness 0.1524)
				)
			)
		)
		(property "Device Type" "C402H22"
			(at 1.1811 -4.2291 90)
			(unlocked yes)
			(layer "F.Fab")
			(hide yes)
			(effects
				(font
					(size 1.016 1.016)
					(thickness 0.1524)
				)
			)
		)
		(duplicate_pad_numbers_are_jumpers no)
		(fp_rect
			(start -0.4318 0.9525)
			(end 0.4318 -0.9525)
			(stroke
				(width 0)
				(type default)
			)
			(fill no)
			(layer "F.CrtYd")
		)
		(fp_rect
			(start -0.4318 0.9525)
			(end 0.4318 -0.9525)
			(stroke
				(width 0)
				(type default)
			)
			(fill no)
			(layer "F.Fab")
		)
		(pad "1" smd custom
			(at 0 -0.4445 90)
			(size 0.1524 0.1524)
			(layers "F.Cu" "F.Mask" "F.Paste")
			(net "P3V3_STBY")
			(options
				(clearance outline)
				(anchor circle)
			)
			(primitives
				(gr_poly
					(pts
						(arc
							(start 0.3048 -0.2032)
							(mid 0.275042 -0.275042)
							(end 0.2032 -0.3048)
						)
						(arc
							(start -0.2032 -0.3048)
							(mid -0.275042 -0.275042)
							(end -0.3048 -0.2032)
						)
						(arc
							(start -0.3048 0.2032)
							(mid -0.275042 0.275042)
							(end -0.2032 0.3048)
						)
						(arc
							(start 0.2032 0.3048)
							(mid 0.275042 0.275042)
							(end 0.3048 0.2032)
						)
					)
					(width 0)
					(fill yes)
				)
			)
		)
		(pad "2" smd custom
			(at 0 0.4445 90)
			(size 0.1524 0.1524)
			(layers "F.Cu" "F.Mask" "F.Paste")
			(net "GND")
			(options
				(clearance outline)
				(anchor circle)
			)
			(primitives
				(gr_poly
					(pts
						(arc
							(start 0.3048 -0.2032)
							(mid 0.275042 -0.275042)
							(end 0.2032 -0.3048)
						)
						(arc
							(start -0.2032 -0.3048)
							(mid -0.275042 -0.275042)
							(end -0.3048 -0.2032)
						)
						(arc
							(start -0.3048 0.2032)
							(mid -0.275042 0.275042)
							(end -0.2032 0.3048)
						)
						(arc
							(start 0.2032 0.3048)
							(mid 0.275042 0.275042)
							(end 0.3048 0.2032)
						)
					)
					(width 0)
					(fill yes)
				)
			)
		)
	)
	(footprint ""
		(layer "F.Cu")
		(at 65.532 -164.582856 180)
		(property "Reference" "R72"
			(at 0 0 180)
			(layer "F.SilkS")
			(hide yes)
			(effects
				(font
					(size 1.27 1.27)
				)
			)
		)
		(property "Value" "10KR2F-2-GP"
			(at 0.064008 -3.993896 180)
			(unlocked yes)
			(layer "F.Fab")
			(hide yes)
			(effects
				(font
					(size 1.016 1.016)
					(thickness 0.1524)
				)
			)
		)
		(property "Device Type" "R402H16"
			(at 0.064008 -5.517896 180)
			(unlocked yes)
			(layer "F.Fab")
			(hide yes)
			(effects
				(font
					(size 1.016 1.016)
					(thickness 0.1524)
				)
			)
		)
		(duplicate_pad_numbers_are_jumpers no)
		(fp_line
			(start 0.508 -0.9398)
			(end -0.508 -0.9398)
			(stroke
				(width 0.1524)
				(type default)
			)
			(layer "F.SilkS")
		)
		(fp_line
			(start -0.508 -0.9398)
			(end -0.508 0.9398)
			(stroke
				(width 0.1524)
				(type default)
			)
			(layer "F.SilkS")
		)
		(fp_rect
			(start -0.508 0.9398)
			(end 0.508 -0.9398)
			(stroke
				(width 0)
				(type default)
			)
			(fill no)
			(layer "F.CrtYd")
		)
		(fp_rect
			(start -0.508 0.9398)
			(end 0.508 -0.9398)
			(stroke
				(width 0)
				(type default)
			)
			(fill no)
			(layer "F.Fab")
		)
		(pad "1" smd custom
			(at 0 -0.4445 180)
			(size 0.1397 0.1397)
			(layers "F.Cu" "F.Mask" "F.Paste")
			(net "P3V3_STBY")
			(options
				(clearance outline)
				(anchor circle)
			)
			(primitives
				(gr_poly
					(pts
						(arc
							(start -0.1778 -0.2794)
							(mid -0.249642 -0.249642)
							(end -0.2794 -0.1778)
						)
						(arc
							(start -0.2794 0.1778)
							(mid -0.249642 0.249642)
							(end -0.1778 0.2794)
						)
						(arc
							(start 0.1778 0.2794)
							(mid 0.249642 0.249642)
							(end 0.2794 0.1778)
						)
						(arc
							(start 0.2794 -0.1778)
							(mid 0.249642 -0.249642)
							(end 0.1778 -0.2794)
						)
					)
					(width 0)
					(fill yes)
				)
			)
		)
		(pad "2" smd custom
			(at 0 0.4445 180)
			(size 0.1397 0.1397)
			(layers "F.Cu" "F.Mask" "F.Paste")
			(net "FM_TPM_PRSNT_RST")
			(options
				(clearance outline)
				(anchor circle)
			)
			(primitives
				(gr_poly
					(pts
						(arc
							(start -0.1778 -0.2794)
							(mid -0.249642 -0.249642)
							(end -0.2794 -0.1778)
						)
						(arc
							(start -0.2794 0.1778)
							(mid -0.249642 0.249642)
							(end -0.1778 0.2794)
						)
						(arc
							(start 0.1778 0.2794)
							(mid 0.249642 0.249642)
							(end 0.2794 0.1778)
						)
						(arc
							(start 0.2794 -0.1778)
							(mid 0.249642 -0.249642)
							(end 0.1778 -0.2794)
						)
					)
					(width 0)
					(fill yes)
				)
			)
		)
	)
	(footprint ""
		(layer "F.Cu")
		(at 10.796524 -136.715246 90)
		(property "Reference" "R208"
			(at 0 0 90)
			(layer "F.SilkS")
			(hide yes)
			(effects
				(font
					(size 1.27 1.27)
				)
			)
		)
		(property "Value" "120R2F-GP"
			(at 0.064008 -3.993896 90)
			(unlocked yes)
			(layer "F.Fab")
			(hide yes)
			(effects
				(font
					(size 1.016 1.016)
					(thickness 0.1524)
				)
			)
		)
		(property "Device Type" "R402H16"
			(at 0.064008 -5.517896 90)
			(unlocked yes)
			(layer "F.Fab")
			(hide yes)
			(effects
				(font
					(size 1.016 1.016)
					(thickness 0.1524)
				)
			)
		)
		(duplicate_pad_numbers_are_jumpers no)
		(fp_line
			(start 0.508 -0.9398)
			(end -0.508 -0.9398)
			(stroke
				(width 0.1524)
				(type default)
			)
			(layer "F.SilkS")
		)
		(fp_line
			(start -0.508 -0.9398)
			(end -0.508 0.9398)
			(stroke
				(width 0.1524)
				(type default)
			)
			(layer "F.SilkS")
		)
		(fp_rect
			(start -0.508 0.9398)
			(end 0.508 -0.9398)
			(stroke
				(width 0)
				(type default)
			)
			(fill no)
			(layer "F.CrtYd")
		)
		(fp_rect
			(start -0.508 0.9398)
			(end 0.508 -0.9398)
			(stroke
				(width 0)
				(type default)
			)
			(fill no)
			(layer "F.Fab")
		)
		(pad "1" smd custom
			(at 0 -0.4445 90)
			(size 0.1397 0.1397)
			(layers "F.Cu" "F.Mask" "F.Paste")
			(net "DDR4_RST_N")
			(options
				(clearance outline)
				(anchor circle)
			)
			(primitives
				(gr_poly
					(pts
						(arc
							(start -0.1778 -0.2794)
							(mid -0.249642 -0.249642)
							(end -0.2794 -0.1778)
						)
						(arc
							(start -0.2794 0.1778)
							(mid -0.249642 0.249642)
							(end -0.1778 0.2794)
						)
						(arc
							(start 0.1778 0.2794)
							(mid 0.249642 0.249642)
							(end 0.2794 0.1778)
						)
						(arc
							(start 0.2794 -0.1778)
							(mid 0.249642 -0.249642)
							(end 0.1778 -0.2794)
						)
					)
					(width 0)
					(fill yes)
				)
			)
		)
		(pad "2" smd custom
			(at 0 0.4445 90)
			(size 0.1397 0.1397)
			(layers "F.Cu" "F.Mask" "F.Paste")
			(net "P1V2_STBY")
			(options
				(clearance outline)
				(anchor circle)
			)
			(primitives
				(gr_poly
					(pts
						(arc
							(start -0.1778 -0.2794)
							(mid -0.249642 -0.249642)
							(end -0.2794 -0.1778)
						)
						(arc
							(start -0.2794 0.1778)
							(mid -0.249642 0.249642)
							(end -0.1778 0.2794)
						)
						(arc
							(start 0.1778 0.2794)
							(mid 0.249642 0.249642)
							(end 0.2794 0.1778)
						)
						(arc
							(start 0.2794 -0.1778)
							(mid 0.249642 -0.249642)
							(end 0.1778 -0.2794)
						)
					)
					(width 0)
					(fill yes)
				)
			)
		)
	)
	(footprint ""
		(layer "F.Cu")
		(at 212.829902 -91.518994 -90)
		(property "Reference" "R828"
			(at 0 0 270)
			(layer "F.SilkS")
			(hide yes)
			(effects
				(font
					(size 1.27 1.27)
				)
			)
		)
		(property "Value" "10KR2F-2-GP"
			(at 0.064008 -3.993896 270)
			(unlocked yes)
			(layer "F.Fab")
			(hide yes)
			(effects
				(font
					(size 1.016 1.016)
					(thickness 0.1524)
				)
			)
		)
		(property "Device Type" "R402H16"
			(at 0.064008 -5.517896 270)
			(unlocked yes)
			(layer "F.Fab")
			(hide yes)
			(effects
				(font
					(size 1.016 1.016)
					(thickness 0.1524)
				)
			)
		)
		(duplicate_pad_numbers_are_jumpers no)
		(fp_line
			(start -0.508 -0.9398)
			(end -0.508 0.9398)
			(stroke
				(width 0.1524)
				(type default)
			)
			(layer "F.SilkS")
		)
		(fp_line
			(start 0.508 -0.9398)
			(end -0.508 -0.9398)
			(stroke
				(width 0.1524)
				(type default)
			)
			(layer "F.SilkS")
		)
		(fp_rect
			(start -0.508 0.9398)
			(end 0.508 -0.9398)
			(stroke
				(width 0)
				(type default)
			)
			(fill no)
			(layer "F.CrtYd")
		)
		(fp_rect
			(start -0.508 0.9398)
			(end 0.508 -0.9398)
			(stroke
				(width 0)
				(type default)
			)
			(fill no)
			(layer "F.Fab")
		)
		(pad "1" smd custom
			(at 0 -0.4445 270)
			(size 0.1397 0.1397)
			(layers "F.Cu" "F.Mask" "F.Paste")
			(net "P3V3_M2_EN")
			(options
				(clearance outline)
				(anchor circle)
			)
			(primitives
				(gr_poly
					(pts
						(arc
							(start -0.1778 -0.2794)
							(mid -0.249642 -0.249642)
							(end -0.2794 -0.1778)
						)
						(arc
							(start -0.2794 0.1778)
							(mid -0.249642 0.249642)
							(end -0.1778 0.2794)
						)
						(arc
							(start 0.1778 0.2794)
							(mid 0.249642 0.249642)
							(end 0.2794 0.1778)
						)
						(arc
							(start 0.2794 -0.1778)
							(mid 0.249642 -0.249642)
							(end 0.1778 -0.2794)
						)
					)
					(width 0)
					(fill yes)
				)
			)
		)
		(pad "2" smd custom
			(at 0 0.4445 270)
			(size 0.1397 0.1397)
			(layers "F.Cu" "F.Mask" "F.Paste")
			(net "P3V3_STBY")
			(options
				(clearance outline)
				(anchor circle)
			)
			(primitives
				(gr_poly
					(pts
						(arc
							(start -0.1778 -0.2794)
							(mid -0.249642 -0.249642)
							(end -0.2794 -0.1778)
						)
						(arc
							(start -0.2794 0.1778)
							(mid -0.249642 0.249642)
							(end -0.1778 0.2794)
						)
						(arc
							(start 0.1778 0.2794)
							(mid 0.249642 0.249642)
							(end 0.2794 0.1778)
						)
						(arc
							(start 0.2794 -0.1778)
							(mid 0.249642 -0.249642)
							(end 0.1778 -0.2794)
						)
					)
					(width 0)
					(fill yes)
				)
			)
		)
	)
	(footprint ""
		(layer "F.Cu")
		(at 45.4152 -130.4036)
		(property "Reference" "TP204"
			(at 0 0 0)
			(layer "F.SilkS")
			(hide yes)
			(effects
				(font
					(size 1.27 1.27)
				)
			)
		)
		(property "Value" "TPAD28-2-GP"
			(at -0.0127 -1.6637 0)
			(unlocked yes)
			(layer "F.Fab")
			(hide yes)
			(effects
				(font
					(size 1.016 1.016)
					(thickness 0.1524)
				)
			)
		)
		(property "Device Type" "TPAD28"
			(at -0.0127 -3.1877 0)
			(unlocked yes)
			(layer "F.Fab")
			(hide yes)
			(effects
				(font
					(size 1.016 1.016)
					(thickness 0.1524)
				)
			)
		)
		(duplicate_pad_numbers_are_jumpers no)
		(fp_poly
			(pts
				(arc
					(start 0.3556 0)
					(mid -0.3556 0)
					(end 0.3556 0)
				)
			)
			(stroke
				(width 0)
				(type default)
			)
			(fill no)
			(layer "F.CrtYd")
		)
		(fp_poly
			(pts
				(arc
					(start 0.6096 0)
					(mid -0.6096 0)
					(end 0.6096 0)
				)
			)
			(stroke
				(width 0)
				(type default)
			)
			(fill no)
			(layer "F.Fab")
		)
		(pad "1" smd circle
			(at 0 0)
			(size 0.7112 0.7112)
			(layers "F.Cu" "F.Mask" "F.Paste")
			(net "BMC_SMB2_DAT_TP")
		)
	)
	(footprint ""
		(layer "F.Cu")
		(at 42.683938 -179.52085)
		(property "Reference" "R488"
			(at 0 0 0)
			(layer "F.SilkS")
			(hide yes)
			(effects
				(font
					(size 1.27 1.27)
				)
			)
		)
		(property "Value" "2K7R2F-GP"
			(at 0.064008 -3.993896 0)
			(unlocked yes)
			(layer "F.Fab")
			(hide yes)
			(effects
				(font
					(size 1.016 1.016)
					(thickness 0.1524)
				)
			)
		)
		(property "Device Type" "R402H16"
			(at 0.064008 -5.517896 0)
			(unlocked yes)
			(layer "F.Fab")
			(hide yes)
			(effects
				(font
					(size 1.016 1.016)
					(thickness 0.1524)
				)
			)
		)
		(duplicate_pad_numbers_are_jumpers no)
		(fp_line
			(start -0.508 -0.9398)
			(end -0.508 0.9398)
			(stroke
				(width 0.1524)
				(type default)
			)
			(layer "F.SilkS")
		)
		(fp_line
			(start 0.508 -0.9398)
			(end -0.508 -0.9398)
			(stroke
				(width 0.1524)
				(type default)
			)
			(layer "F.SilkS")
		)
		(fp_rect
			(start -0.508 0.9398)
			(end 0.508 -0.9398)
			(stroke
				(width 0)
				(type default)
			)
			(fill no)
			(layer "F.CrtYd")
		)
		(fp_rect
			(start -0.508 0.9398)
			(end 0.508 -0.9398)
			(stroke
				(width 0)
				(type default)
			)
			(fill no)
			(layer "F.Fab")
		)
		(pad "1" smd custom
			(at 0 -0.4445)
			(size 0.1397 0.1397)
			(layers "F.Cu" "F.Mask" "F.Paste")
			(net "P3V3_STBY_LL")
			(options
				(clearance outline)
				(anchor circle)
			)
			(primitives
				(gr_poly
					(pts
						(arc
							(start -0.1778 -0.2794)
							(mid -0.249642 -0.249642)
							(end -0.2794 -0.1778)
						)
						(arc
							(start -0.2794 0.1778)
							(mid -0.249642 0.249642)
							(end -0.1778 0.2794)
						)
						(arc
							(start 0.1778 0.2794)
							(mid 0.249642 0.249642)
							(end 0.2794 0.1778)
						)
						(arc
							(start 0.2794 -0.1778)
							(mid 0.249642 -0.249642)
							(end 0.1778 -0.2794)
						)
					)
					(width 0)
					(fill yes)
				)
			)
		)
		(pad "2" smd custom
			(at 0 0.4445)
			(size 0.1397 0.1397)
			(layers "F.Cu" "F.Mask" "F.Paste")
			(net "P3V3_STBY_LL_R")
			(options
				(clearance outline)
				(anchor circle)
			)
			(primitives
				(gr_poly
					(pts
						(arc
							(start -0.1778 -0.2794)
							(mid -0.249642 -0.249642)
							(end -0.2794 -0.1778)
						)
						(arc
							(start -0.2794 0.1778)
							(mid -0.249642 0.249642)
							(end -0.1778 0.2794)
						)
						(arc
							(start 0.1778 0.2794)
							(mid 0.249642 0.249642)
							(end 0.2794 0.1778)
						)
						(arc
							(start 0.2794 -0.1778)
							(mid 0.249642 -0.249642)
							(end 0.1778 -0.2794)
						)
					)
					(width 0)
					(fill yes)
				)
			)
		)
	)
	(footprint ""
		(layer "F.Cu")
		(at 23.058882 -171.227496 90)
		(property "Reference" "C232"
			(at 0 0 90)
			(layer "F.SilkS")
			(hide yes)
			(effects
				(font
					(size 1.27 1.27)
				)
			)
		)
		(property "Value" "SC10U6D3V5KX-4GP"
			(at -0.0762 -6.1214 90)
			(unlocked yes)
			(layer "F.Fab")
			(hide yes)
			(effects
				(font
					(size 1.016 1.016)
					(thickness 0.1524)
				)
			)
		)
		(property "Device Type" "C805H58"
			(at -0.0762 -8.1534 90)
			(unlocked yes)
			(layer "F.Fab")
			(hide yes)
			(effects
				(font
					(size 1.016 1.016)
					(thickness 0.1524)
				)
			)
		)
		(duplicate_pad_numbers_are_jumpers no)
		(fp_line
			(start 0.635 0)
			(end -0.635 0)
			(stroke
				(width 0.508)
				(type default)
			)
			(layer "F.SilkS")
		)
		(fp_rect
			(start -0.9652 1.778)
			(end 0.9652 -1.778)
			(stroke
				(width 0)
				(type default)
			)
			(fill no)
			(layer "F.CrtYd")
		)
		(fp_poly
			(pts
				(xy -0.9652 -1.778) (xy 0.9652 -1.778) (xy 0.9652 1.778) (xy -0.9652 1.778)
			)
			(stroke
				(width 0)
				(type default)
			)
			(fill no)
			(layer "F.Fab")
		)
		(pad "1" smd rect
			(at 0 -0.9652 90)
			(size 1.397 1.143)
			(layers "F.Cu" "F.Mask" "F.Paste")
			(net "P1V8_STBY")
		)
		(pad "2" smd rect
			(at 0 0.9652 90)
			(size 1.397 1.143)
			(layers "F.Cu" "F.Mask" "F.Paste")
			(net "GND")
		)
	)
)
